===================================================================================================
QUANTA Computer Inc. SWB CPLD RELEASE NOTES for GT SWB
===================================================================================================
Project Name            : GT SWB
CPLD Vender             : Lattice(Weikeng)
CPLD Device             : LCMXO3LF-9400C-5BG484C
HDL FW Version          : 0x00020001
Build Date              : 2023/04/17
Checksum                : 0x51BB
===================================================================================================
                             IMPORTANT INSTALLATION NOTES
===================================================================================================
I. WARNING:
  1. N/A

II. CPLD FW Upgrade:
  1. Using Dongle: USB Blaster
  2. Using oBMC online update: fw-util swb --update swb_cpld XXX.pldm

===================================================================================================
                             KNOWN ISSUES/WORKAROUNDS
===================================================================================================
- N/A

===================================================================================================
                             FEATURES ADDED/MODIFY
===================================================================================================
0x02000001:
- Initial release for power on.

0x00000001:
- Modify SYS_PWR_READY_N to current behavier.
- Add SMBus register for BMC.
- Modify hold time to solve timing issue.

0x00000002:
- Modify PCIe reset domain following combine design by GTT and GTI.
- Change PEX power reset follow host reset.
- Change SYS_PWR_READY_N follow host reset.
- Change clock enable of devices follow P3V3 power good to solve power leakage issue.
- Change NIC power sequence to keep AUX_Power_Mode_ON during DC off state.
- Change the SMBus regiset offset 0x08 to 0x0F to correct P12V power good of NIC.

0x00010000:
- Modify SSD clock enable to AND power enable of P3V3 for solving power leakage issue.

0x00020000:
- Modify PEX system reset following the first rising edge of host reset.
- Add SMBus regisetr for BIC.

0x00020001:
- Modify SYS_PWR_READY_N following RST_PEX_SYS_N.
- Add unused signal to SMBus register.

===================================================================================================
                             FEATURES REMOVED
===================================================================================================
0x02000001:
- N/A
- Initial release for power on.

0x00000001:
- N/A

0x00000002:
- N/A

0x00010000:
- N/A

0x00020000:
- N/A

0x00020001:
- N/A

===================================================================================================
                             ISSUES FIXED
===================================================================================================
0x02000001:
- Initial release for power on debug.

0x00000001:
- N/A

0x00000002:
- N/A

0x00010000:
- N/A

0x00020000:
- N/A

0x00020001:
- N/A
[END OF RELEASE NOTES]
